
Section 2 - Conflicts on Net Synonyms
--------------------------------------

DRAWING = @TIMECARD_LIB.TIMECARD(SCH_1)
NET_NAME = XP5R0V
   OPF: VOLTAGE = 5.0V; NET = XP5R0V
 * SCH: VOLTAGE = 5.0

Logical and Physical Net Conflicts 
----------------------------------

DRAWING = @TIMECARD_LIB.TIMECARD(SCH_1)
NET_NAME = R_MAC_BITE OUT
   PNN = R_MAC_BITEOUT
NET_NAME = FPGA_IN_MAC_BITE OUT
   PNN = FPGA_IN_MAC_BITEOUT
